(kicad_pcb
	(version 20260206)
	(generator "pcbnew")
	(generator_version "10.0")
	(general
		(thickness 1.6)
		(legacy_teardrops no)
	)
	(paper "A4")
	(title_block
		(title "04192023_DAF0TMB3IC0_F0TG_MB_C_brd_V02_OCP.brd")
		(comment 1 "Grand Teton / footprint 583 of 8354 (J27), pads 1-113 of 291")
	)
	(layers
		(0 "F.Cu" signal "TOP")
		(4 "In1.Cu" signal "GND")
		(6 "In2.Cu" signal "IN1")
		(8 "In3.Cu" signal "GND1")
		(10 "In4.Cu" signal "IN2")
		(12 "In5.Cu" signal "GND2")
		(14 "In6.Cu" signal "IN3")
		(16 "In7.Cu" signal "GND3")
		(18 "In8.Cu" signal "VCC")
		(20 "In9.Cu" signal "VCC1")
		(22 "In10.Cu" signal "GND4")
		(24 "In11.Cu" signal "IN4")
		(26 "In12.Cu" signal "GND5")
		(28 "In13.Cu" signal "IN5")
		(30 "In14.Cu" signal "GND6")
		(32 "In15.Cu" signal "IN6")
		(34 "In16.Cu" signal "GND7")
		(2 "B.Cu" signal "BOTTOM")
		(9 "F.Adhes" user "F.Adhesive")
		(11 "B.Adhes" user "B.Adhesive")
		(13 "F.Paste" user "Package Geometry/Pastemask Top")
		(15 "B.Paste" user "Package Geometry/Pastemask Bottom")
		(5 "F.SilkS" user "Ref Des/Silkscreen Top")
		(7 "B.SilkS" user "Ref Des/Silkscreen Bottom")
		(1 "F.Mask" user "Board Geometry/Soldermask Top")
		(3 "B.Mask" user "Board Geometry/Soldermask Bottom")
		(17 "Dwgs.User" user "User.Drawings")
		(19 "Cmts.User" user "User.Comments")
		(21 "Eco1.User" user "User.Eco1")
		(23 "Eco2.User" user "User.Eco2")
		(25 "Edge.Cuts" user "Board Geometry/Outline")
		(27 "Margin" user)
		(31 "F.CrtYd" user "Package Geometry/Place Bound Top")
		(29 "B.CrtYd" user "Package Geometry/Place Bound Bottom")
		(35 "F.Fab" user "Ref Des/Assembly Top")
		(33 "B.Fab" user "Ref Des/Assembly Bottom")
	)
	(footprint ""
		(layer "F.Cu")
		(at 174.022004 -255.560322 180)
		(property "Reference" "J27"
			(at -2.7178 -81.857088 0)
			(unlocked yes)
			(layer "F.SilkS")
			(effects
				(font
					(size 0.7874 0.5842)
					(thickness 0.1524)
				)
			)
		)
		(property "Value" ""
			(at 0 0 180)
			(layer "F.Fab")
			(effects
				(font
					(size 1.27 1.27)
				)
			)
		)
		(duplicate_pad_numbers_are_jumpers no)
		(pad "1" smd rect
			(at -2.050034 -63.324994 90)
			(size 0.519938 1.4986)
			(layers "F.Cu" "F.Mask" "F.Paste")
			(net "P12V_MEM_CPU1")
		)
		(pad "2" smd rect
			(at -2.050034 -62.47511 90)
			(size 0.519938 1.4986)
			(layers "F.Cu" "F.Mask" "F.Paste")
			(net "Net_2354")
		)
		(pad "3" smd rect
			(at -2.050034 -61.624972 90)
			(size 0.519938 1.4986)
			(layers "F.Cu" "F.Mask" "F.Paste")
			(net "P3V3_AUX")
		)
		(pad "4" smd rect
			(at -2.050034 -60.775088 90)
			(size 0.519938 1.4986)
			(layers "F.Cu" "F.Mask" "F.Paste")
			(net "I3C_SPD_DDRH_CPU1_SCL")
		)
		(pad "5" smd rect
			(at -2.050034 -59.92495 90)
			(size 0.519938 1.4986)
			(layers "F.Cu" "F.Mask" "F.Paste")
			(net "I3C_SPD_DDRH_CPU1_SDA")
		)
		(pad "6" smd rect
			(at -2.050034 -59.075066 90)
			(size 0.519938 1.4986)
			(layers "F.Cu" "F.Mask" "F.Paste")
			(net "GND")
		)
		(pad "7" smd rect
			(at -2.050034 -58.224928 90)
			(size 0.519938 1.4986)
			(layers "F.Cu" "F.Mask" "F.Paste")
			(net "M_H_CPU1_SA_DQ<0>")
		)
		(pad "8" smd rect
			(at -2.050034 -57.375044 90)
			(size 0.519938 1.4986)
			(layers "F.Cu" "F.Mask" "F.Paste")
			(net "GND")
		)
		(pad "9" smd rect
			(at -2.050034 -56.524906 90)
			(size 0.519938 1.4986)
			(layers "F.Cu" "F.Mask" "F.Paste")
			(net "M_H_CPU1_SA_DQ<1>")
		)
		(pad "10" smd rect
			(at -2.050034 -55.675022 90)
			(size 0.519938 1.4986)
			(layers "F.Cu" "F.Mask" "F.Paste")
			(net "GND")
		)
		(pad "11" smd rect
			(at -2.050034 -54.824884 90)
			(size 0.519938 1.4986)
			(layers "F.Cu" "F.Mask" "F.Paste")
			(net "M_H_CPU1_SA_DQS_DP<0>")
		)
		(pad "12" smd rect
			(at -2.050034 -53.975 90)
			(size 0.519938 1.4986)
			(layers "F.Cu" "F.Mask" "F.Paste")
			(net "M_H_CPU1_SA_DQS_DN<0>")
		)
		(pad "13" smd rect
			(at -2.050034 -53.125116 90)
			(size 0.519938 1.4986)
			(layers "F.Cu" "F.Mask" "F.Paste")
			(net "GND")
		)
		(pad "14" smd rect
			(at -2.050034 -52.274978 90)
			(size 0.519938 1.4986)
			(layers "F.Cu" "F.Mask" "F.Paste")
			(net "M_H_CPU1_SA_DQ<4>")
		)
		(pad "15" smd rect
			(at -2.050034 -51.425094 90)
			(size 0.519938 1.4986)
			(layers "F.Cu" "F.Mask" "F.Paste")
			(net "GND")
		)
		(pad "16" smd rect
			(at -2.050034 -50.574956 90)
			(size 0.519938 1.4986)
			(layers "F.Cu" "F.Mask" "F.Paste")
			(net "M_H_CPU1_SA_DQ<5>")
		)
		(pad "17" smd rect
			(at -2.050034 -49.725072 90)
			(size 0.519938 1.4986)
			(layers "F.Cu" "F.Mask" "F.Paste")
			(net "GND")
		)
		(pad "18" smd rect
			(at -2.050034 -48.874934 90)
			(size 0.519938 1.4986)
			(layers "F.Cu" "F.Mask" "F.Paste")
			(net "M_H_CPU1_SA_DQ<8>")
		)
		(pad "19" smd rect
			(at -2.050034 -48.02505 90)
			(size 0.519938 1.4986)
			(layers "F.Cu" "F.Mask" "F.Paste")
			(net "GND")
		)
		(pad "20" smd rect
			(at -2.050034 -47.174912 90)
			(size 0.519938 1.4986)
			(layers "F.Cu" "F.Mask" "F.Paste")
			(net "M_H_CPU1_SA_DQ<9>")
		)
		(pad "21" smd rect
			(at -2.050034 -46.325028 90)
			(size 0.519938 1.4986)
			(layers "F.Cu" "F.Mask" "F.Paste")
			(net "GND")
		)
		(pad "22" smd rect
			(at -2.050034 -45.47489 90)
			(size 0.519938 1.4986)
			(layers "F.Cu" "F.Mask" "F.Paste")
			(net "M_H_CPU1_SA_DQS_DP<1>")
		)
		(pad "23" smd rect
			(at -2.050034 -44.625006 90)
			(size 0.519938 1.4986)
			(layers "F.Cu" "F.Mask" "F.Paste")
			(net "M_H_CPU1_SA_DQS_DN<1>")
		)
		(pad "24" smd rect
			(at -2.050034 -43.775122 90)
			(size 0.519938 1.4986)
			(layers "F.Cu" "F.Mask" "F.Paste")
			(net "GND")
		)
		(pad "25" smd rect
			(at -2.050034 -42.924984 90)
			(size 0.519938 1.4986)
			(layers "F.Cu" "F.Mask" "F.Paste")
			(net "M_H_CPU1_SA_DQ<12>")
		)
		(pad "26" smd rect
			(at -2.050034 -42.0751 90)
			(size 0.519938 1.4986)
			(layers "F.Cu" "F.Mask" "F.Paste")
			(net "GND")
		)
		(pad "27" smd rect
			(at -2.050034 -41.224962 90)
			(size 0.519938 1.4986)
			(layers "F.Cu" "F.Mask" "F.Paste")
			(net "M_H_CPU1_SA_DQ<13>")
		)
		(pad "28" smd rect
			(at -2.050034 -40.375078 90)
			(size 0.519938 1.4986)
			(layers "F.Cu" "F.Mask" "F.Paste")
			(net "GND")
		)
		(pad "29" smd rect
			(at -2.050034 -39.52494 90)
			(size 0.519938 1.4986)
			(layers "F.Cu" "F.Mask" "F.Paste")
			(net "M_H_CPU1_SA_DQ<16>")
		)
		(pad "30" smd rect
			(at -2.050034 -38.675056 90)
			(size 0.519938 1.4986)
			(layers "F.Cu" "F.Mask" "F.Paste")
			(net "GND")
		)
		(pad "31" smd rect
			(at -2.050034 -37.824918 90)
			(size 0.519938 1.4986)
			(layers "F.Cu" "F.Mask" "F.Paste")
			(net "M_H_CPU1_SA_DQ<17>")
		)
		(pad "32" smd rect
			(at -2.050034 -36.975034 90)
			(size 0.519938 1.4986)
			(layers "F.Cu" "F.Mask" "F.Paste")
			(net "GND")
		)
		(pad "33" smd rect
			(at -2.050034 -36.124896 90)
			(size 0.519938 1.4986)
			(layers "F.Cu" "F.Mask" "F.Paste")
			(net "M_H_CPU1_SA_DQS_DP<2>")
		)
		(pad "34" smd rect
			(at -2.050034 -35.275012 90)
			(size 0.519938 1.4986)
			(layers "F.Cu" "F.Mask" "F.Paste")
			(net "M_H_CPU1_SA_DQS_DN<2>")
		)
		(pad "35" smd rect
			(at -2.050034 -34.425128 90)
			(size 0.519938 1.4986)
			(layers "F.Cu" "F.Mask" "F.Paste")
			(net "GND")
		)
		(pad "36" smd rect
			(at -2.050034 -33.57499 90)
			(size 0.519938 1.4986)
			(layers "F.Cu" "F.Mask" "F.Paste")
			(net "M_H_CPU1_SA_DQ<20>")
		)
		(pad "37" smd rect
			(at -2.050034 -32.725106 90)
			(size 0.519938 1.4986)
			(layers "F.Cu" "F.Mask" "F.Paste")
			(net "GND")
		)
		(pad "38" smd rect
			(at -2.050034 -31.874968 90)
			(size 0.519938 1.4986)
			(layers "F.Cu" "F.Mask" "F.Paste")
			(net "M_H_CPU1_SA_DQ<21>")
		)
		(pad "39" smd rect
			(at -2.050034 -31.025084 90)
			(size 0.519938 1.4986)
			(layers "F.Cu" "F.Mask" "F.Paste")
			(net "GND")
		)
		(pad "40" smd rect
			(at -2.050034 -30.174946 90)
			(size 0.519938 1.4986)
			(layers "F.Cu" "F.Mask" "F.Paste")
			(net "M_H_CPU1_SA_DQ<24>")
		)
		(pad "41" smd rect
			(at -2.050034 -29.325062 90)
			(size 0.519938 1.4986)
			(layers "F.Cu" "F.Mask" "F.Paste")
			(net "GND")
		)
		(pad "42" smd rect
			(at -2.050034 -28.474924 90)
			(size 0.519938 1.4986)
			(layers "F.Cu" "F.Mask" "F.Paste")
			(net "M_H_CPU1_SA_DQ<25>")
		)
		(pad "43" smd rect
			(at -2.050034 -27.62504 90)
			(size 0.519938 1.4986)
			(layers "F.Cu" "F.Mask" "F.Paste")
			(net "GND")
		)
		(pad "44" smd rect
			(at -2.050034 -26.774902 90)
			(size 0.519938 1.4986)
			(layers "F.Cu" "F.Mask" "F.Paste")
			(net "M_H_CPU1_SA_DQS_DP<3>")
		)
		(pad "45" smd rect
			(at -2.050034 -25.925018 90)
			(size 0.519938 1.4986)
			(layers "F.Cu" "F.Mask" "F.Paste")
			(net "M_H_CPU1_SA_DQS_DN<3>")
		)
		(pad "46" smd rect
			(at -2.050034 -25.07488 90)
			(size 0.519938 1.4986)
			(layers "F.Cu" "F.Mask" "F.Paste")
			(net "GND")
		)
		(pad "47" smd rect
			(at -2.050034 -24.224996 90)
			(size 0.519938 1.4986)
			(layers "F.Cu" "F.Mask" "F.Paste")
			(net "M_H_CPU1_SA_DQ<28>")
		)
		(pad "48" smd rect
			(at -2.050034 -23.375112 90)
			(size 0.519938 1.4986)
			(layers "F.Cu" "F.Mask" "F.Paste")
			(net "GND")
		)
		(pad "49" smd rect
			(at -2.050034 -22.524974 90)
			(size 0.519938 1.4986)
			(layers "F.Cu" "F.Mask" "F.Paste")
			(net "M_H_CPU1_SA_DQ<29>")
		)
		(pad "50" smd rect
			(at -2.050034 -21.67509 90)
			(size 0.519938 1.4986)
			(layers "F.Cu" "F.Mask" "F.Paste")
			(net "GND")
		)
		(pad "51" smd rect
			(at -2.050034 -20.824952 90)
			(size 0.519938 1.4986)
			(layers "F.Cu" "F.Mask" "F.Paste")
			(net "M_H_CPU1_SA_CB<0>")
		)
		(pad "52" smd rect
			(at -2.050034 -19.975068 90)
			(size 0.519938 1.4986)
			(layers "F.Cu" "F.Mask" "F.Paste")
			(net "GND")
		)
		(pad "53" smd rect
			(at -2.050034 -19.12493 90)
			(size 0.519938 1.4986)
			(layers "F.Cu" "F.Mask" "F.Paste")
			(net "M_H_CPU1_SA_CB<1>")
		)
		(pad "54" smd rect
			(at -2.050034 -18.275046 90)
			(size 0.519938 1.4986)
			(layers "F.Cu" "F.Mask" "F.Paste")
			(net "GND")
		)
		(pad "55" smd rect
			(at -2.050034 -17.424908 90)
			(size 0.519938 1.4986)
			(layers "F.Cu" "F.Mask" "F.Paste")
			(net "M_H_CPU1_SA_DQS_DP<4>")
		)
		(pad "56" smd rect
			(at -2.050034 -16.575024 90)
			(size 0.519938 1.4986)
			(layers "F.Cu" "F.Mask" "F.Paste")
			(net "M_H_CPU1_SA_DQS_DN<4>")
		)
		(pad "57" smd rect
			(at -2.050034 -15.724886 90)
			(size 0.519938 1.4986)
			(layers "F.Cu" "F.Mask" "F.Paste")
			(net "GND")
		)
		(pad "58" smd rect
			(at -2.050034 -14.875002 90)
			(size 0.519938 1.4986)
			(layers "F.Cu" "F.Mask" "F.Paste")
			(net "M_H_CPU1_SA_CB<4>")
		)
		(pad "59" smd rect
			(at -2.050034 -14.025118 90)
			(size 0.519938 1.4986)
			(layers "F.Cu" "F.Mask" "F.Paste")
			(net "GND")
		)
		(pad "60" smd rect
			(at -2.050034 -13.17498 90)
			(size 0.519938 1.4986)
			(layers "F.Cu" "F.Mask" "F.Paste")
			(net "M_H_CPU1_SA_CB<5>")
		)
		(pad "61" smd rect
			(at -2.050034 -12.325096 90)
			(size 0.519938 1.4986)
			(layers "F.Cu" "F.Mask" "F.Paste")
			(net "GND")
		)
		(pad "62" smd rect
			(at -2.050034 -11.474958 90)
			(size 0.519938 1.4986)
			(layers "F.Cu" "F.Mask" "F.Paste")
			(net "M_H_CPU1_ALERT_N")
		)
		(pad "63" smd rect
			(at -2.050034 -10.625074 90)
			(size 0.519938 1.4986)
			(layers "F.Cu" "F.Mask" "F.Paste")
			(net "GND")
		)
		(pad "64" smd rect
			(at -2.050034 -9.774936 90)
			(size 0.519938 1.4986)
			(layers "F.Cu" "F.Mask" "F.Paste")
			(net "M_H_CPU1_SA_CS_N<0>")
		)
		(pad "65" smd rect
			(at -2.050034 -8.925052 90)
			(size 0.519938 1.4986)
			(layers "F.Cu" "F.Mask" "F.Paste")
			(net "GND")
		)
		(pad "66" smd rect
			(at -2.050034 -8.074914 90)
			(size 0.519938 1.4986)
			(layers "F.Cu" "F.Mask" "F.Paste")
			(net "M_H_CPU1_SA_CA<0>")
		)
		(pad "67" smd rect
			(at -2.050034 -7.22503 90)
			(size 0.519938 1.4986)
			(layers "F.Cu" "F.Mask" "F.Paste")
			(net "GND")
		)
		(pad "68" smd rect
			(at -2.050034 -6.374892 90)
			(size 0.519938 1.4986)
			(layers "F.Cu" "F.Mask" "F.Paste")
			(net "M_H_CPU1_SA_CA<2>")
		)
		(pad "69" smd rect
			(at -2.050034 -5.525008 90)
			(size 0.519938 1.4986)
			(layers "F.Cu" "F.Mask" "F.Paste")
			(net "GND")
		)
		(pad "70" smd rect
			(at -2.050034 -4.675124 90)
			(size 0.519938 1.4986)
			(layers "F.Cu" "F.Mask" "F.Paste")
			(net "M_H_CPU1_SA_CA<4>")
		)
		(pad "71" smd rect
			(at -2.050034 -3.824986 90)
			(size 0.519938 1.4986)
			(layers "F.Cu" "F.Mask" "F.Paste")
			(net "GND")
		)
		(pad "72" smd rect
			(at -2.050034 -2.975102 90)
			(size 0.519938 1.4986)
			(layers "F.Cu" "F.Mask" "F.Paste")
			(net "M_H_CPU1_SA_CA<6>")
		)
		(pad "73" smd rect
			(at -2.050034 -2.124964 90)
			(size 0.519938 1.4986)
			(layers "F.Cu" "F.Mask" "F.Paste")
			(net "GND")
		)
		(pad "74" smd rect
			(at -2.050034 -1.27508 90)
			(size 0.519938 1.4986)
			(layers "F.Cu" "F.Mask" "F.Paste")
			(net "M_H_CPU1_SA_PAR")
		)
		(pad "75" smd rect
			(at -2.050034 -0.424942 90)
			(size 0.519938 1.4986)
			(layers "F.Cu" "F.Mask" "F.Paste")
			(net "GND")
		)
		(pad "76" smd rect
			(at -2.050034 5.525008 90)
			(size 0.519938 1.4986)
			(layers "F.Cu" "F.Mask" "F.Paste")
			(net "M_H_CPU1_SB_CA<0>")
		)
		(pad "77" smd rect
			(at -2.050034 6.374892 90)
			(size 0.519938 1.4986)
			(layers "F.Cu" "F.Mask" "F.Paste")
			(net "GND")
		)
		(pad "78" smd rect
			(at -2.050034 7.22503 90)
			(size 0.519938 1.4986)
			(layers "F.Cu" "F.Mask" "F.Paste")
			(net "M_H_CPU1_SB_CA<2>")
		)
		(pad "79" smd rect
			(at -2.050034 8.074914 90)
			(size 0.519938 1.4986)
			(layers "F.Cu" "F.Mask" "F.Paste")
			(net "GND")
		)
		(pad "80" smd rect
			(at -2.050034 8.925052 90)
			(size 0.519938 1.4986)
			(layers "F.Cu" "F.Mask" "F.Paste")
			(net "M_H_CPU1_SB_CA<4>")
		)
		(pad "81" smd rect
			(at -2.050034 9.774936 90)
			(size 0.519938 1.4986)
			(layers "F.Cu" "F.Mask" "F.Paste")
			(net "GND")
		)
		(pad "82" smd rect
			(at -2.050034 10.625074 90)
			(size 0.519938 1.4986)
			(layers "F.Cu" "F.Mask" "F.Paste")
			(net "M_H_CPU1_SB_CA<6>")
		)
		(pad "83" smd rect
			(at -2.050034 11.474958 90)
			(size 0.519938 1.4986)
			(layers "F.Cu" "F.Mask" "F.Paste")
			(net "GND")
		)
		(pad "84" smd rect
			(at -2.050034 12.325096 90)
			(size 0.519938 1.4986)
			(layers "F.Cu" "F.Mask" "F.Paste")
			(net "M_H_CPU1_SB_CS_N<0>")
		)
		(pad "85" smd rect
			(at -2.050034 13.17498 90)
			(size 0.519938 1.4986)
			(layers "F.Cu" "F.Mask" "F.Paste")
			(net "GND")
		)
		(pad "86" smd rect
			(at -2.050034 14.025118 90)
			(size 0.519938 1.4986)
			(layers "F.Cu" "F.Mask" "F.Paste")
			(net "M_H_CPU1_SA_RSP<0>")
		)
		(pad "87" smd rect
			(at -2.050034 14.875002 90)
			(size 0.519938 1.4986)
			(layers "F.Cu" "F.Mask" "F.Paste")
			(net "M_H_CPU1_SB_RSP<0>")
		)
		(pad "88" smd rect
			(at -2.050034 15.724886 90)
			(size 0.519938 1.4986)
			(layers "F.Cu" "F.Mask" "F.Paste")
			(net "GND")
		)
		(pad "89" smd rect
			(at -2.050034 16.575024 90)
			(size 0.519938 1.4986)
			(layers "F.Cu" "F.Mask" "F.Paste")
			(net "M_H_CPU1_SB_CB<4>")
		)
		(pad "90" smd rect
			(at -2.050034 17.424908 90)
			(size 0.519938 1.4986)
			(layers "F.Cu" "F.Mask" "F.Paste")
			(net "GND")
		)
		(pad "91" smd rect
			(at -2.050034 18.275046 90)
			(size 0.519938 1.4986)
			(layers "F.Cu" "F.Mask" "F.Paste")
			(net "M_H_CPU1_SB_CB<5>")
		)
		(pad "92" smd rect
			(at -2.050034 19.12493 90)
			(size 0.519938 1.4986)
			(layers "F.Cu" "F.Mask" "F.Paste")
			(net "GND")
		)
		(pad "93" smd rect
			(at -2.050034 19.975068 90)
			(size 0.519938 1.4986)
			(layers "F.Cu" "F.Mask" "F.Paste")
			(net "M_H_CPU1_SB_DQS_DP<9>")
		)
		(pad "94" smd rect
			(at -2.050034 20.824952 90)
			(size 0.519938 1.4986)
			(layers "F.Cu" "F.Mask" "F.Paste")
			(net "M_H_CPU1_SB_DQS_DN<9>")
		)
		(pad "95" smd rect
			(at -2.050034 21.67509 90)
			(size 0.519938 1.4986)
			(layers "F.Cu" "F.Mask" "F.Paste")
			(net "GND")
		)
		(pad "96" smd rect
			(at -2.050034 22.524974 90)
			(size 0.519938 1.4986)
			(layers "F.Cu" "F.Mask" "F.Paste")
			(net "M_H_CPU1_SB_CB<0>")
		)
		(pad "97" smd rect
			(at -2.050034 23.375112 90)
			(size 0.519938 1.4986)
			(layers "F.Cu" "F.Mask" "F.Paste")
			(net "GND")
		)
		(pad "98" smd rect
			(at -2.050034 24.224996 90)
			(size 0.519938 1.4986)
			(layers "F.Cu" "F.Mask" "F.Paste")
			(net "M_H_CPU1_SB_CB<1>")
		)
		(pad "99" smd rect
			(at -2.050034 25.07488 90)
			(size 0.519938 1.4986)
			(layers "F.Cu" "F.Mask" "F.Paste")
			(net "GND")
		)
		(pad "100" smd rect
			(at -2.050034 25.925018 90)
			(size 0.519938 1.4986)
			(layers "F.Cu" "F.Mask" "F.Paste")
			(net "M_H_CPU1_SB_DQ<0>")
		)
		(pad "101" smd rect
			(at -2.050034 26.774902 90)
			(size 0.519938 1.4986)
			(layers "F.Cu" "F.Mask" "F.Paste")
			(net "GND")
		)
		(pad "102" smd rect
			(at -2.050034 27.62504 90)
			(size 0.519938 1.4986)
			(layers "F.Cu" "F.Mask" "F.Paste")
			(net "M_H_CPU1_SB_DQ<1>")
		)
		(pad "103" smd rect
			(at -2.050034 28.474924 90)
			(size 0.519938 1.4986)
			(layers "F.Cu" "F.Mask" "F.Paste")
			(net "GND")
		)
		(pad "104" smd rect
			(at -2.050034 29.325062 90)
			(size 0.519938 1.4986)
			(layers "F.Cu" "F.Mask" "F.Paste")
			(net "M_H_CPU1_SB_DQS_DP<0>")
		)
		(pad "105" smd rect
			(at -2.050034 30.174946 90)
			(size 0.519938 1.4986)
			(layers "F.Cu" "F.Mask" "F.Paste")
			(net "M_H_CPU1_SB_DQS_DN<0>")
		)
		(pad "106" smd rect
			(at -2.050034 31.025084 90)
			(size 0.519938 1.4986)
			(layers "F.Cu" "F.Mask" "F.Paste")
			(net "GND")
		)
		(pad "107" smd rect
			(at -2.050034 31.874968 90)
			(size 0.519938 1.4986)
			(layers "F.Cu" "F.Mask" "F.Paste")
			(net "M_H_CPU1_SB_DQ<4>")
		)
		(pad "108" smd rect
			(at -2.050034 32.725106 90)
			(size 0.519938 1.4986)
			(layers "F.Cu" "F.Mask" "F.Paste")
			(net "GND")
		)
		(pad "109" smd rect
			(at -2.050034 33.57499 90)
			(size 0.519938 1.4986)
			(layers "F.Cu" "F.Mask" "F.Paste")
			(net "M_H_CPU1_SB_DQ<5>")
		)
		(pad "110" smd rect
			(at -2.050034 34.425128 90)
			(size 0.519938 1.4986)
			(layers "F.Cu" "F.Mask" "F.Paste")
			(net "GND")
		)
		(pad "111" smd rect
			(at -2.050034 35.275012 90)
			(size 0.519938 1.4986)
			(layers "F.Cu" "F.Mask" "F.Paste")
			(net "M_H_CPU1_SB_DQ<8>")
		)
		(pad "112" smd rect
			(at -2.050034 36.124896 90)
			(size 0.519938 1.4986)
			(layers "F.Cu" "F.Mask" "F.Paste")
			(net "GND")
		)
		(pad "113" smd rect
			(at -2.050034 36.975034 90)
			(size 0.519938 1.4986)
			(layers "F.Cu" "F.Mask" "F.Paste")
			(net "M_H_CPU1_SB_DQ<9>")
		)
	)
)
